# TIMECARD (Time Appliance Project (Time Card)) — schematic netlist excerpt (pin names and nets, part order shuffled) for the footprints in the layout excerpt that follows; sources: Cadence DE-HDL packaged netlist, KiCad conversion of R4006-B0001-02_R01.brd

TP29  TP_PIONT  pkg TP010CT020B030_PTH  page 25 : \1\ = SMA2_SIG_IN_BF_EN_N

U13  74HCT2G125DP_TSSOP8  NC7WV125K8X  pkg SOP8_091_P0197_H035  page 23
  \1oe*\  = SMA3_SIG_OUT_BF_EN_N
  \1a\  = UNNAMED_12_74HCT2G125DPTSSOP8_I
  \2y\  = BF_ANT3_IN
  GND  = SG
  \2a\  = BF_SMA3_SIG_IO_CONN
  \1y\  = BF_SMA3_SIG_IO_CONN
  \2oe*\  = SMA3_SIG_IN_BF_EN_N
  VCC  = XP3R3V_FPGA

(kicad_pcb
	(version 20260206)
	(generator "pcbnew")
	(generator_version "10.0")
	(general
		(thickness 1.6)
		(legacy_teardrops no)
	)
	(paper "A4")
	(title_block
		(title "timecard-production-celestica-r4006 — R4006-B0001-02_R01.brd")
		(comment 1 "Time Appliance Project (Time Card) / footprints 502-503 of 1113")
	)
	(layers
		(0 "F.Cu" signal "TOP")
		(4 "In1.Cu" signal "L02_GND1")
		(6 "In2.Cu" signal "L03_SIG1")
		(8 "In3.Cu" signal "L04_GND2")
		(10 "In4.Cu" signal "L05_VCC1")
		(12 "In5.Cu" signal "L06_VCC2")
		(14 "In6.Cu" signal "L07_GND3")
		(16 "In7.Cu" signal "L08_SIG2")
		(18 "In8.Cu" signal "L09_GND4")
		(2 "B.Cu" signal "BOTTOM")
		(9 "F.Adhes" user "F.Adhesive")
		(11 "B.Adhes" user "B.Adhesive")
		(13 "F.Paste" user "Package Geometry/Pastemask Top")
		(15 "B.Paste" user "Package Geometry/Pastemask Bottom")
		(5 "F.SilkS" user "Ref Des/Silkscreen Top")
		(7 "B.SilkS" user "Ref Des/Silkscreen Bottom")
		(1 "F.Mask" user "Board Geometry/Soldermask Top")
		(3 "B.Mask" user "Board Geometry/Soldermask Bottom")
		(17 "Dwgs.User" user "User.Drawings")
		(19 "Cmts.User" user "User.Comments")
		(21 "Eco1.User" user "User.Eco1")
		(23 "Eco2.User" user "User.Eco2")
		(25 "Edge.Cuts" user "Board Geometry/Outline")
		(27 "Margin" user)
		(31 "F.CrtYd" user "Package Geometry/Place Bound Top")
		(29 "B.CrtYd" user "Package Geometry/Place Bound Bottom")
		(35 "F.Fab" user "Ref Des/Assembly Top")
		(33 "B.Fab" user "Ref Des/Assembly Bottom")
	)
	(footprint ""
		(layer "F.Cu")
		(at 13.899896 -32.599884 -90)
		(property "Reference" "U13"
			(at 1.738884 -2.649474 90)
			(unlocked yes)
			(layer "F.SilkS")
			(effects
				(font
					(size 0.7874 0.5842)
					(thickness 0.1524)
				)
			)
		)
		(property "Value" ""
			(at 0 0 270)
			(layer "F.Fab")
			(effects
				(font
					(size 1.27 1.27)
				)
			)
		)
		(property "Device Type" "74HCT2G125DP_TSSOP8-G220-00055A"
			(at 0 2.413 270)
			(unlocked yes)
			(layer "F.Fab")
			(hide yes)
			(effects
				(font
					(size 0.7874 0.5842)
					(thickness 0.1524)
				)
			)
		)
		(property "User Part Number" "PARTNUM*"
			(at 0 3.6068 270)
			(unlocked yes)
			(layer "Cmts.User")
			(hide yes)
			(effects
				(font
					(size 0.7874 0.5842)
					(thickness 0.1524)
				)
			)
		)
		(duplicate_pad_numbers_are_jumpers no)
		(fp_line
			(start -2.426716 1.304036)
			(end -2.426716 -1.304036)
			(stroke
				(width 0.1)
				(type default)
			)
			(layer "F.SilkS")
		)
		(fp_line
			(start 2.426716 1.304036)
			(end -2.426716 1.304036)
			(stroke
				(width 0.1)
				(type default)
			)
			(layer "F.SilkS")
		)
		(fp_line
			(start -2.426716 -1.304036)
			(end 2.426716 -1.304036)
			(stroke
				(width 0.1)
				(type default)
			)
			(layer "F.SilkS")
		)
		(fp_line
			(start 2.426716 -1.304036)
			(end 2.426716 1.304036)
			(stroke
				(width 0.1)
				(type default)
			)
			(layer "F.SilkS")
		)
		(fp_poly
			(pts
				(arc
					(start -3.21437 -1.465326)
					(mid -3.21437 -0.703326)
					(end -3.21437 -1.465326)
				)
			)
			(stroke
				(width 0)
				(type default)
			)
			(fill yes)
			(layer "F.SilkS")
		)
		(fp_poly
			(pts
				(xy -2.680716 1.558036) (xy 2.680716 1.558036) (xy 2.680716 -1.558036) (xy -2.680716 -1.558036)
			)
			(stroke
				(width 0)
				(type default)
			)
			(fill no)
			(layer "F.CrtYd")
		)
		(fp_line
			(start -1.199896 1.050036)
			(end 1.199896 1.050036)
			(stroke
				(width 0.1)
				(type default)
			)
			(layer "F.Fab")
		)
		(fp_line
			(start 1.199896 1.050036)
			(end 1.199896 -1.050036)
			(stroke
				(width 0.1)
				(type default)
			)
			(layer "F.Fab")
		)
		(fp_line
			(start -1.199896 -1.050036)
			(end -1.199896 1.050036)
			(stroke
				(width 0.1)
				(type default)
			)
			(layer "F.Fab")
		)
		(fp_line
			(start 1.199896 -1.050036)
			(end -1.199896 -1.050036)
			(stroke
				(width 0.1)
				(type default)
			)
			(layer "F.Fab")
		)
		(fp_poly
			(pts
				(arc
					(start -1.94437 -1.211326)
					(mid -1.94437 -0.449326)
					(end -1.94437 -1.211326)
				)
			)
			(stroke
				(width 0)
				(type default)
			)
			(fill yes)
			(layer "F.Fab")
		)
		(fp_text user "4"
			(at -1.813052 1.834896 0)
			(unlocked yes)
			(layer "F.SilkS")
			(effects
				(font
					(size 0.635 0.4064)
					(thickness 0.1524)
				)
			)
		)
		(fp_text user "5"
			(at 2.913634 1.453896 0)
			(unlocked yes)
			(layer "F.SilkS")
			(effects
				(font
					(size 0.635 0.4064)
					(thickness 0.1524)
				)
			)
		)
		(fp_text user "8"
			(at 2.913634 -1.340104 0)
			(unlocked yes)
			(layer "F.SilkS")
			(effects
				(font
					(size 0.635 0.4064)
					(thickness 0.1524)
				)
			)
		)
		(fp_text user "4"
			(at -1.767332 0.945896 0)
			(unlocked yes)
			(layer "F.Fab")
			(effects
				(font
					(size 0.7874 0.5842)
					(thickness 0.1524)
				)
			)
		)
		(fp_text user "5"
			(at 1.947926 0.710184 0)
			(unlocked yes)
			(layer "F.Fab")
			(effects
				(font
					(size 0.7874 0.5842)
					(thickness 0.1524)
				)
			)
		)
		(fp_text user "8"
			(at 1.96088 -0.910844 0)
			(unlocked yes)
			(layer "F.Fab")
			(effects
				(font
					(size 0.7874 0.5842)
					(thickness 0.1524)
				)
			)
		)
		(pad "1" smd rect
			(at -1.690116 -0.749808 270)
			(size 0.9652 0.3048)
			(layers "F.Cu" "F.Mask" "F.Paste")
			(net "SMA3_SIG_OUT_BF_EN_N")
		)
		(pad "2" smd rect
			(at -1.690116 -0.249936 270)
			(size 0.9652 0.3048)
			(layers "F.Cu" "F.Mask" "F.Paste")
			(net "UNNAMED_12_74HCT2G125DPTSSOP8_I")
		)
		(pad "3" smd rect
			(at -1.690116 0.249936 270)
			(size 0.9652 0.3048)
			(layers "F.Cu" "F.Mask" "F.Paste")
			(net "BF_ANT3_IN")
		)
		(pad "4" smd rect
			(at -1.690116 0.749808 270)
			(size 0.9652 0.3048)
			(layers "F.Cu" "F.Mask" "F.Paste")
			(net "SG")
		)
		(pad "5" smd rect
			(at 1.690116 0.749808 270)
			(size 0.9652 0.3048)
			(layers "F.Cu" "F.Mask" "F.Paste")
			(net "BF_SMA3_SIG_IO_CONN")
		)
		(pad "6" smd rect
			(at 1.690116 0.249936 270)
			(size 0.9652 0.3048)
			(layers "F.Cu" "F.Mask" "F.Paste")
			(net "BF_SMA3_SIG_IO_CONN")
		)
		(pad "7" smd rect
			(at 1.690116 -0.249936 270)
			(size 0.9652 0.3048)
			(layers "F.Cu" "F.Mask" "F.Paste")
			(net "SMA3_SIG_IN_BF_EN_N")
		)
		(pad "8" smd rect
			(at 1.690116 -0.749808 270)
			(size 0.9652 0.3048)
			(layers "F.Cu" "F.Mask" "F.Paste")
			(net "XP3R3V_FPGA")
		)
	)
	(footprint ""
		(layer "F.Cu")
		(at 13.843 -43.434)
		(property "Reference" "TP29"
			(at 0.7366 -0.60325 0)
			(unlocked yes)
			(layer "F.SilkS")
			(effects
				(font
					(size 0.635 0.4064)
					(thickness 0.1524)
				)
				(justify left)
			)
		)
		(property "Value" ""
			(at 0 0 0)
			(layer "F.Fab")
			(effects
				(font
					(size 1.27 1.27)
				)
			)
		)
		(property "Device Type" "TP_PIONT-TP010CT020B030_PTH-TPA"
			(at -1.341882 0.996696 0)
			(unlocked yes)
			(layer "F.Fab")
			(hide yes)
			(effects
				(font
					(size 0.7874 0.5842)
					(thickness 0.000001)
				)
				(justify left)
			)
		)
		(duplicate_pad_numbers_are_jumpers no)
		(fp_poly
			(pts
				(arc
					(start 0.889 0)
					(mid -0.889 0)
					(end 0.889 0)
				)
			)
			(stroke
				(width 0)
				(type default)
			)
			(fill no)
			(layer "B.CrtYd")
		)
		(fp_poly
			(pts
				(arc
					(start 0.889 0)
					(mid -0.889 0)
					(end 0.889 0)
				)
			)
			(stroke
				(width 0)
				(type default)
			)
			(fill no)
			(layer "F.CrtYd")
		)
		(pad "1" thru_hole circle
			(at 0 0)
			(size 0.508 0.508)
			(drill 0.254)
			(layers "*.Cu" "*.Mask")
			(remove_unused_layers no)
			(net "SMA2_SIG_IN_BF_EN_N")
			(clearance 0.1016)
			(padstack
				(mode front_inner_back)
				(layer "Inner"
					(shape circle)
					(size 0.508 0.508)
					(clearance 0.1016)
				)
				(layer "B.Cu"
					(shape circle)
					(size 0.762 0.762)
					(clearance -0.0254)
				)
			)
		)
	)
)
